(kicad_pcb
	(version 20260206)
	(generator "pcbnew")
	(generator_version "10.0")
	(general
		(thickness 1.6)
		(legacy_teardrops no)
	)
	(paper "A4")
	(title_block
		(title "v1-chassis-manager — T6M_CM_d_v01_1031_1645.brd")
		(comment 1 "Open CloudServer (Microsoft) / footprints 1292-1294 of 2512")
	)
	(layers
		(0 "F.Cu" signal "TOP")
		(4 "In1.Cu" signal "GND1")
		(6 "In2.Cu" signal "IN1")
		(8 "In3.Cu" signal "VCC1")
		(10 "In4.Cu" signal "VCC2")
		(12 "In5.Cu" signal "GND2")
		(14 "In6.Cu" signal "IN2")
		(16 "In7.Cu" signal "IN3")
		(18 "In8.Cu" signal "GND3")
		(2 "B.Cu" signal "BOTTOM")
		(9 "F.Adhes" user "F.Adhesive")
		(11 "B.Adhes" user "B.Adhesive")
		(13 "F.Paste" user "Package Geometry/Pastemask Top")
		(15 "B.Paste" user "Package Geometry/Pastemask Bottom")
		(5 "F.SilkS" user "Ref Des/Silkscreen Top")
		(7 "B.SilkS" user "Ref Des/Silkscreen Bottom")
		(1 "F.Mask" user "Board Geometry/Soldermask Top")
		(3 "B.Mask" user "Board Geometry/Soldermask Bottom")
		(17 "Dwgs.User" user "User.Drawings")
		(19 "Cmts.User" user "User.Comments")
		(21 "Eco1.User" user "User.Eco1")
		(23 "Eco2.User" user "User.Eco2")
		(25 "Edge.Cuts" user "Board Geometry/Outline")
		(27 "Margin" user)
		(31 "F.CrtYd" user "Package Geometry/Place Bound Top")
		(29 "B.CrtYd" user "Package Geometry/Place Bound Bottom")
		(35 "F.Fab" user "Ref Des/Assembly Top")
		(33 "B.Fab" user "Ref Des/Assembly Bottom")
	)
	(footprint ""
		(layer "F.Cu")
		(at 47.60214 -166.43985 90)
		(property "Reference" "R541"
			(at -130.36804 -3.317748 90)
			(unlocked yes)
			(layer "F.SilkS")
			(effects
				(font
					(size 0.7874 0.5842)
					(thickness 0.1524)
				)
				(justify left)
			)
		)
		(property "Value" ""
			(at 0 0 90)
			(layer "F.Fab")
			(effects
				(font
					(size 1.27 1.27)
				)
			)
		)
		(duplicate_pad_numbers_are_jumpers no)
		(fp_line
			(start 0.7874 -0.4064)
			(end 0.7874 0.4064)
			(stroke
				(width 0.1524)
				(type default)
			)
			(layer "F.SilkS")
		)
		(fp_line
			(start -0.7874 -0.4064)
			(end 0.7874 -0.4064)
			(stroke
				(width 0.1524)
				(type default)
			)
			(layer "F.SilkS")
		)
		(fp_line
			(start 0.7874 0.4064)
			(end -0.7874 0.4064)
			(stroke
				(width 0.1524)
				(type default)
			)
			(layer "F.SilkS")
		)
		(fp_line
			(start -0.7874 0.4064)
			(end -0.7874 -0.4064)
			(stroke
				(width 0.1524)
				(type default)
			)
			(layer "F.SilkS")
		)
		(fp_poly
			(pts
				(xy -0.508 0.2794) (xy -0.508 0.2286) (xy -0.635 0.2286) (xy -0.635 -0.254) (xy -0.5334 -0.254)
				(xy -0.5334 -0.2794) (xy 0.5334 -0.2794) (xy 0.5334 -0.254) (xy 0.635 -0.254) (xy 0.635 0.254) (xy 0.5334 0.254)
				(xy 0.5334 0.2794)
			)
			(stroke
				(width 0)
				(type default)
			)
			(fill no)
			(layer "F.CrtYd")
		)
		(pad "1" smd rect
			(at 0.40005 0 90)
			(size 0.4572 0.508)
			(layers "F.Cu" "F.Mask" "F.Paste")
			(net "P3V3_NODE1")
		)
		(pad "2" smd rect
			(at -0.40005 0 90)
			(size 0.4572 0.508)
			(layers "F.Cu" "F.Mask" "F.Paste")
			(net "LAN1_AUX_PWR")
		)
	)
	(footprint ""
		(layer "F.Cu")
		(at 123.89358 -130.473196 -90)
		(property "Reference" ""
			(at 0 0 270)
			(layer "F.SilkS")
			(hide yes)
			(effects
				(font
					(size 1.27 1.27)
				)
			)
		)
		(property "Value" ""
			(at 0 0 270)
			(layer "F.Fab")
			(effects
				(font
					(size 1.27 1.27)
				)
			)
		)
		(duplicate_pad_numbers_are_jumpers no)
		(fp_poly
			(pts
				(arc
					(start 0 -1.4986)
					(mid 0 1.4986)
					(end 0 -1.4986)
				)
			)
			(stroke
				(width 0)
				(type default)
			)
			(fill no)
			(layer "F.CrtYd")
		)
		(pad "1" smd circle
			(at 0 0 270)
			(size 0.9906 0.9906)
			(layers "F.Cu" "F.Mask" "F.Paste")
			(net "Net_34")
		)
		(zone
			(layer "F.Cu")
			(hatch none 0.5)
			(connect_pads
				(clearance 0)
			)
			(min_thickness 0.25)
			(keepout
				(tracks not_allowed)
				(vias allowed)
				(pads allowed)
				(copperpour not_allowed)
				(footprints allowed)
			)
			(placement
				(enabled no)
				(sheetname "")
			)
			(fill
				(thermal_gap 0.5)
				(thermal_bridge_width 0.5)
				(island_removal_mode 0)
			)
			(polygon
				(pts
					(arc
						(start 125.51918 -130.473196)
						(mid 122.26798 -130.473196)
						(end 125.51918 -130.473196)
					)
				)
			)
		)
	)
	(footprint ""
		(layer "F.Cu")
		(at 8.1915 -97.303336 90)
		(property "Reference" "D29"
			(at 3.693668 0.060452 90)
			(unlocked yes)
			(layer "F.SilkS")
			(effects
				(font
					(size 0.7874 0.5842)
					(thickness 0.1524)
				)
				(justify left)
			)
		)
		(property "Value" ""
			(at 0 0 90)
			(layer "F.Fab")
			(effects
				(font
					(size 1.27 1.27)
				)
			)
		)
		(duplicate_pad_numbers_are_jumpers no)
		(fp_line
			(start 3.429 -1.397)
			(end -3.175 -1.397)
			(stroke
				(width 0.1524)
				(type default)
			)
			(layer "F.SilkS")
		)
		(fp_line
			(start 3.302 -1.397)
			(end 3.302 1.397)
			(stroke
				(width 0.1524)
				(type default)
			)
			(layer "F.SilkS")
		)
		(fp_line
			(start -3.175 -1.397)
			(end -3.175 1.397)
			(stroke
				(width 0.1524)
				(type default)
			)
			(layer "F.SilkS")
		)
		(fp_line
			(start 0.299974 -0.500126)
			(end 0.299974 0.500126)
			(stroke
				(width 0.1524)
				(type default)
			)
			(layer "F.SilkS")
		)
		(fp_line
			(start -0.299974 -0.500126)
			(end -0.299974 0.500126)
			(stroke
				(width 0.1524)
				(type default)
			)
			(layer "F.SilkS")
		)
		(fp_line
			(start 0.199898 0)
			(end -0.299974 -0.500126)
			(stroke
				(width 0.1524)
				(type default)
			)
			(layer "F.SilkS")
		)
		(fp_line
			(start -0.299974 0.500126)
			(end 0.199898 0)
			(stroke
				(width 0.1524)
				(type default)
			)
			(layer "F.SilkS")
		)
		(fp_line
			(start 3.429 1.397)
			(end 3.429 -1.397)
			(stroke
				(width 0.1524)
				(type default)
			)
			(layer "F.SilkS")
		)
		(fp_line
			(start 3.302 1.397)
			(end 3.299968 1.400048)
			(stroke
				(width 0.1524)
				(type default)
			)
			(layer "F.SilkS")
		)
		(fp_line
			(start 3.175 1.397)
			(end 3.175 -1.397)
			(stroke
				(width 0.1524)
				(type default)
			)
			(layer "F.SilkS")
		)
		(fp_line
			(start -3.175 1.397)
			(end 3.429 1.397)
			(stroke
				(width 0.1524)
				(type default)
			)
			(layer "F.SilkS")
		)
		(fp_poly
			(pts
				(xy -2.6416 1.397) (xy -2.6416 1.016) (xy -3.0226 1.016) (xy -3.0226 -1.016) (xy -2.667 -1.016)
				(xy -2.667 -1.397) (xy 2.667 -1.397) (xy 2.667 -1.016) (xy 3.0226 -1.016) (xy 3.0226 1.016) (xy 2.667 1.016)
				(xy 2.667 1.397)
			)
			(stroke
				(width 0)
				(type default)
			)
			(fill no)
			(layer "F.CrtYd")
		)
		(pad "1" smd rect
			(at -2.249932 0 270)
			(size 1.524 2.032)
			(layers "F.Cu" "F.Mask" "F.Paste")
			(net "P12V_DBG")
		)
		(pad "2" smd rect
			(at 2.249932 0 90)
			(size 1.524 2.032)
			(layers "F.Cu" "F.Mask" "F.Paste")
			(net "P12V_PDB")
		)
	)
)
